# BARRELEYE-G2-SXM2 RISER BOARD-EVT-X00-BOM-X01-20171102_Final.xls.xlsx — Component Qual Tracker (bom)
|  |  |  |  |  |  |  |  | Part to be included on following build: |  |  |  |  |  |
| Item No. | Part Group | Single/Sole/Multi | Item Description | ODM P/N | Customer PN | Vendor | Vendor P/N | X00 Build | X01 Build | X02 Build | Qual Build | Qualification Target Date | Qualification Complete Date |
|  | VR Controllers |  |  |  |  | Vendor #1 |  |  |  |  |  |  |  |
|  |  |  |  |  |  | Vendor #2 |  |  |  |  |  |  |  |
|  | FETS |  |  |  |  | Vendor #1 |  |  |  |  |  |  |  |
|  |  |  |  |  |  | Vendor #2 |  |  |  |  |  |  |  |
|  | INDUCTORS |  |  |  |  | Vendor #1 |  |  |  |  |  |  |  |
|  |  |  |  |  |  | Vendor #2 |  |  |  |  |  |  |  |
|  | VREG CAPS |  |  |  |  | Vendor #1 |  |  |  |  |  |  |  |
|  |  |  |  |  |  | Vendor #2 |  |  |  |  |  |  |  |
|  | CRYSTALS |  |  |  |  | Vendor #1 |  |  |  |  |  |  |  |
|  |  |  |  |  |  | Vendor #2 |  |  |  |  |  |  |  |
|  | CONNECTORS |  |  |  |  | Vendor #1 |  |  |  |  |  |  |  |
|  |  |  |  |  |  | Vendor #2 |  |  |  |  |  |  |  |
|  | IC'S |  |  |  |  | Vendor #1 |  |  |  |  |  |  |  |
|  |  |  |  |  |  | Vendor #2 |  |  |  |  |  |  |  |
|  | MISC. |  |  |  |  | Vendor #1 |  |  |  |  |  |  |  |
|  | (HEATSINKS) |  |  |  |  | Vendor #2 |  |  |  |  |  |  |  |
